(kicad_pcb
	(version 20241229)
	(generator "pcbnew")
	(generator_version "9.0")
	(general
		(thickness 1.294)
		(legacy_teardrops no)
	)
	(paper "A3")
	(title_block
		(title "Kintex 410T devboard")
		(date "2024-04-03")
		(rev "1.1.2")
		(comment 9 "footprints 298-301 of 975")
	)
	(layers
		(0 "F.Cu" mixed)
		(4 "In1.Cu" power)
		(6 "In2.Cu" power)
		(8 "In3.Cu" mixed)
		(10 "In4.Cu" power)
		(12 "In5.Cu" mixed)
		(14 "In6.Cu" power)
		(16 "In7.Cu" mixed)
		(18 "In8.Cu" power)
		(2 "B.Cu" mixed)
		(9 "F.Adhes" user "F.Adhesive")
		(11 "B.Adhes" user "B.Adhesive")
		(13 "F.Paste" user)
		(15 "B.Paste" user)
		(5 "F.SilkS" user "F.Silkscreen")
		(7 "B.SilkS" user "B.Silkscreen")
		(1 "F.Mask" user)
		(3 "B.Mask" user)
		(17 "Dwgs.User" user "User.Drawings")
		(19 "Cmts.User" user "User.Comments")
		(21 "Eco1.User" user "User.Eco1")
		(23 "Eco2.User" user "User.Eco2")
		(25 "Edge.Cuts" user)
		(27 "Margin" user)
		(31 "F.CrtYd" user "F.Courtyard")
		(29 "B.CrtYd" user "B.Courtyard")
		(35 "F.Fab" user)
		(33 "B.Fab" user)
	)
	(footprint "antmicro-footprints:C_0402_1005Metric"
		(layer "F.Cu")
		(at 240.25 147.2 180)
		(descr "Capacitor SMD 0402")
		(tags "capacitor SMD 0402")
		(property "Reference" "C245"
			(at 1.8 -2.2 180)
			(layer "F.SilkS")
			(effects
				(font
					(size 0.7 0.7)
					(thickness 0.15)
				)
				(justify left bottom)
			)
		)
		(property "Value" "C_100n_0402"
			(at 0 1.169 180)
			(layer "F.Fab")
			(effects
				(font
					(size 0.7 0.7)
					(thickness 0.15)
				)
				(justify left bottom)
			)
		)
		(property "Description" "SMD Multilayer Ceramic Capacitor, 0.1 µF, 50 V, 0402 [1005 Metric], ± 10%, X5R, GRM Series"
			(at 0 0 180)
			(layer "F.Fab")
			(hide yes)
			(effects
				(font
					(size 1.27 1.27)
					(thickness 0.15)
				)
			)
		)
		(property "Author" "Antmicro"
			(at 480.5 294.4 0)
			(layer "F.Fab")
			(hide yes)
			(effects
				(font
					(size 1 1)
					(thickness 0.15)
				)
			)
		)
		(property "Dielectric" "X5R"
			(at 480.5 294.4 0)
			(layer "F.Fab")
			(hide yes)
			(effects
				(font
					(size 1 1)
					(thickness 0.15)
				)
			)
		)
		(property "License" "Apache-2.0"
			(at 480.5 294.4 0)
			(layer "F.Fab")
			(hide yes)
			(effects
				(font
					(size 1 1)
					(thickness 0.15)
				)
			)
		)
		(property "MPN" "GRM155R61H104KE14D"
			(at 480.5 294.4 0)
			(layer "F.Fab")
			(hide yes)
			(effects
				(font
					(size 1 1)
					(thickness 0.15)
				)
			)
		)
		(property "Manufacturer" "Murata"
			(at 480.5 294.4 0)
			(layer "F.Fab")
			(hide yes)
			(effects
				(font
					(size 1 1)
					(thickness 0.15)
				)
			)
		)
		(property "Val" "100n"
			(at 480.5 294.4 0)
			(layer "F.Fab")
			(hide yes)
			(effects
				(font
					(size 1 1)
					(thickness 0.15)
				)
			)
		)
		(property "Voltage" "50V"
			(at 480.5 294.4 0)
			(layer "F.Fab")
			(hide yes)
			(effects
				(font
					(size 1 1)
					(thickness 0.15)
				)
			)
		)
		(sheetname "USB PHY")
		(sheetfile "usb-phy.kicad_sch")
		(attr smd)
		(fp_rect
			(start -0.925 -0.47)
			(end 0.925 0.47)
			(stroke
				(width 0.05)
				(type default)
			)
			(fill no)
			(layer "F.CrtYd")
		)
		(fp_line
			(start 0.504 0.248)
			(end -0.494 0.248)
			(stroke
				(width 0.15)
				(type solid)
			)
			(layer "F.Fab")
		)
		(fp_line
			(start 0.504 -0.25)
			(end 0.504 0.248)
			(stroke
				(width 0.15)
				(type solid)
			)
			(layer "F.Fab")
		)
		(fp_line
			(start -0.494 0.248)
			(end -0.494 -0.25)
			(stroke
				(width 0.15)
				(type solid)
			)
			(layer "F.Fab")
		)
		(fp_line
			(start -0.494 -0.25)
			(end 0.504 -0.25)
			(stroke
				(width 0.15)
				(type solid)
			)
			(layer "F.Fab")
		)
		(pad "1" smd roundrect
			(at -0.48 0 180)
			(size 0.59 0.64)
			(layers "F.Cu" "F.Mask" "F.Paste")
			(roundrect_rratio 0.25)
			(net 1 "GND")
			(pintype "passive")
		)
		(pad "2" smd roundrect
			(at 0.48 0 180)
			(size 0.59 0.64)
			(layers "F.Cu" "F.Mask" "F.Paste")
			(roundrect_rratio 0.25)
			(net 707 "/USB PHY/FTDI_3V3")
			(pintype "passive")
		)
	)
	(footprint "antmicro-footprints:SW_KMR211NGLFS_SMD"
		(layer "F.Cu")
		(at 177.978 73.62 -90)
		(property "Reference" "S1"
			(at 3.58 1.778 0)
			(layer "F.SilkS")
			(effects
				(font
					(size 0.7 0.7)
					(thickness 0.15)
				)
				(justify left bottom)
			)
		)
		(property "Value" "SW_KMR211NGLFS_SMD"
			(at -3 3 270)
			(layer "F.Fab")
			(effects
				(font
					(size 0.7 0.7)
					(thickness 0.15)
				)
				(justify left bottom)
			)
		)
		(property "Description" "Tactile Switch, KMR 2 Series, Top Actuated, Surface Mount, Oval Button, 120 gf, 50mA at 32VDC"
			(at 0 0 270)
			(layer "F.Fab")
			(hide yes)
			(effects
				(font
					(size 1.27 1.27)
					(thickness 0.15)
				)
			)
		)
		(property "Author" "Antmicro"
			(at 104.358 251.598 0)
			(layer "F.Fab")
			(hide yes)
			(effects
				(font
					(size 1 1)
					(thickness 0.15)
				)
			)
		)
		(property "License" "Apache-2.0"
			(at 104.358 251.598 0)
			(layer "F.Fab")
			(hide yes)
			(effects
				(font
					(size 1 1)
					(thickness 0.15)
				)
			)
		)
		(property "MPN" "KMR211NGLFS"
			(at 104.358 251.598 0)
			(layer "F.Fab")
			(hide yes)
			(effects
				(font
					(size 1 1)
					(thickness 0.15)
				)
			)
		)
		(property "Manufacturer" "C&K"
			(at 104.358 251.598 0)
			(layer "F.Fab")
			(hide yes)
			(effects
				(font
					(size 1 1)
					(thickness 0.15)
				)
			)
		)
		(sheetname "FPGA Config")
		(sheetfile "fpga-config.kicad_sch")
		(attr smd)
		(fp_line
			(start -2.1 1.601)
			(end -2.1 1.48)
			(stroke
				(width 0.15)
				(type solid)
			)
			(layer "F.SilkS")
		)
		(fp_line
			(start 2.101 1.601)
			(end -2.1 1.601)
			(stroke
				(width 0.15)
				(type solid)
			)
			(layer "F.SilkS")
		)
		(fp_line
			(start 2.101 1.601)
			(end 2.101 1.48)
			(stroke
				(width 0.15)
				(type solid)
			)
			(layer "F.SilkS")
		)
		(fp_line
			(start 2.101 -1.58)
			(end 2.101 -1.459)
			(stroke
				(width 0.15)
				(type solid)
			)
			(layer "F.SilkS")
		)
		(fp_line
			(start -2.1 -1.6)
			(end -2.1 -1.499)
			(stroke
				(width 0.15)
				(type solid)
			)
			(layer "F.SilkS")
		)
		(fp_line
			(start 2.101 -1.6)
			(end -2.1 -1.6)
			(stroke
				(width 0.15)
				(type solid)
			)
			(layer "F.SilkS")
		)
		(fp_rect
			(start 2.751 1.75)
			(end -2.748 -1.749)
			(stroke
				(width 0.05)
				(type solid)
			)
			(fill no)
			(layer "F.CrtYd")
		)
		(fp_line
			(start -2.1 1.601)
			(end 2.101 1.601)
			(stroke
				(width 0.15)
				(type solid)
			)
			(layer "F.Fab")
		)
		(fp_line
			(start 2.101 1.601)
			(end 2.101 -1.6)
			(stroke
				(width 0.15)
				(type solid)
			)
			(layer "F.Fab")
		)
		(fp_line
			(start 0.25 0.802)
			(end -0.248 0.802)
			(stroke
				(width 0.15)
				(type solid)
			)
			(layer "F.Fab")
		)
		(fp_line
			(start -0.248 -0.8)
			(end 0.25 -0.8)
			(stroke
				(width 0.15)
				(type solid)
			)
			(layer "F.Fab")
		)
		(fp_line
			(start -2.1 -1.6)
			(end -2.1 1.601)
			(stroke
				(width 0.15)
				(type solid)
			)
			(layer "F.Fab")
		)
		(fp_line
			(start 2.101 -1.6)
			(end -2.1 -1.6)
			(stroke
				(width 0.15)
				(type solid)
			)
			(layer "F.Fab")
		)
		(fp_arc
			(start -0.248 0.802)
			(mid -1.050001 0.001)
			(end -0.248 -0.8)
			(stroke
				(width 0.15)
				(type solid)
			)
			(layer "F.Fab")
		)
		(fp_arc
			(start 0.25 -0.8)
			(mid 1.051001 0.001)
			(end 0.25 0.802)
			(stroke
				(width 0.15)
				(type solid)
			)
			(layer "F.Fab")
		)
		(pad "1" smd rect
			(at -2.048 -0.8 90)
			(size 0.9 1)
			(layers "F.Cu" "F.Mask" "F.Paste")
			(net 301 "/FPGA Config/PROGRAM_B")
			(pinfunction "1")
			(pintype "passive")
		)
		(pad "2" smd rect
			(at 2.05 -0.8 90)
			(size 0.9 1)
			(layers "F.Cu" "F.Mask" "F.Paste")
			(net 301 "/FPGA Config/PROGRAM_B")
			(pinfunction "2")
			(pintype "passive")
		)
		(pad "3" smd rect
			(at -2.048 0.802 90)
			(size 0.9 1)
			(layers "F.Cu" "F.Mask" "F.Paste")
			(net 1 "GND")
			(pinfunction "3")
			(pintype "passive")
		)
		(pad "4" smd rect
			(at 2.05 0.802 90)
			(size 0.9 1)
			(layers "F.Cu" "F.Mask" "F.Paste")
			(net 1 "GND")
			(pinfunction "4")
			(pintype "passive")
		)
	)
	(footprint "antmicro-footprints:LED_0603_1608Metric_G"
		(layer "F.Cu")
		(at 261.5 88.6)
		(descr "LED SMD 0603 Green")
		(tags "LED SMD 0603 Green")
		(property "Reference" "D20"
			(at -1.05 1.55 0)
			(layer "F.SilkS")
			(effects
				(font
					(size 0.7 0.7)
					(thickness 0.15)
				)
				(justify left bottom)
			)
		)
		(property "Value" "LED_G_0603_KP-1608CGCK"
			(at 0 1.6 0)
			(layer "F.Fab")
			(effects
				(font
					(size 0.7 0.7)
					(thickness 0.15)
				)
				(justify left bottom)
			)
		)
		(property "Description" "LED, Green, SMD, 0603, 20 mA, 2.1 V, 570 nm"
			(at 0 0 0)
			(layer "F.Fab")
			(hide yes)
			(effects
				(font
					(size 1.27 1.27)
					(thickness 0.15)
				)
			)
		)
		(property "Author" "Antmicro"
			(at 0 0 0)
			(layer "F.Fab")
			(hide yes)
			(effects
				(font
					(size 1 1)
					(thickness 0.15)
				)
			)
		)
		(property "Color" "Green"
			(at 0 0 0)
			(layer "F.Fab")
			(hide yes)
			(effects
				(font
					(size 1 1)
					(thickness 0.15)
				)
			)
		)
		(property "License" "Apache-2.0"
			(at 0 0 0)
			(layer "F.Fab")
			(hide yes)
			(effects
				(font
					(size 1 1)
					(thickness 0.15)
				)
			)
		)
		(property "MPN" "KP-1608CGCK"
			(at 0 0 0)
			(layer "F.Fab")
			(hide yes)
			(effects
				(font
					(size 1 1)
					(thickness 0.15)
				)
			)
		)
		(property "Manufacturer" "Kingbright"
			(at 0 0 0)
			(layer "F.Fab")
			(hide yes)
			(effects
				(font
					(size 1 1)
					(thickness 0.15)
				)
			)
		)
		(sheetname "User GPIO + LED + button + DIP switch")
		(sheetfile "user-gpio.kicad_sch")
		(attr smd)
		(fp_line
			(start -1.18 -0.319)
			(end -1.18 0.321)
			(stroke
				(width 0.15)
				(type solid)
			)
			(layer "F.SilkS")
		)
		(fp_line
			(start -0.094672 0.001008)
			(end -0.24 0.001008)
			(stroke
				(width 0.1)
				(type solid)
			)
			(layer "F.SilkS")
		)
		(fp_line
			(start -0.094672 0.001008)
			(end 0.105328 -0.198992)
			(stroke
				(width 0.1)
				(type solid)
			)
			(layer "F.SilkS")
		)
		(fp_line
			(start -0.094672 0.201008)
			(end -0.094672 -0.198992)
			(stroke
				(width 0.1)
				(type solid)
			)
			(layer "F.SilkS")
		)
		(fp_line
			(start 0.105328 0.001008)
			(end 0.24 0.001)
			(stroke
				(width 0.1)
				(type solid)
			)
			(layer "F.SilkS")
		)
		(fp_line
			(start 0.105328 0.201008)
			(end -0.094672 0.001008)
			(stroke
				(width 0.1)
				(type solid)
			)
			(layer "F.SilkS")
		)
		(fp_line
			(start 0.105328 0.201008)
			(end 0.105328 -0.198992)
			(stroke
				(width 0.1)
				(type solid)
			)
			(layer "F.SilkS")
		)
		(fp_line
			(start 0.22 -0.35)
			(end -0.22 -0.35)
			(stroke
				(width 0.15)
				(type solid)
			)
			(layer "F.SilkS")
		)
		(fp_line
			(start 0.22 0.35)
			(end -0.22 0.35)
			(stroke
				(width 0.15)
				(type solid)
			)
			(layer "F.SilkS")
		)
		(fp_rect
			(start 1.25 0.65)
			(end -1.25 -0.65)
			(stroke
				(width 0.05)
				(type solid)
			)
			(fill no)
			(layer "F.CrtYd")
		)
		(fp_line
			(start -0.199 -0.202)
			(end -0.199 0.1)
			(stroke
				(width 0.15)
				(type solid)
			)
			(layer "F.Fab")
		)
		(fp_line
			(start -0.199 0)
			(end -0.597 0)
			(stroke
				(width 0.15)
				(type solid)
			)
			(layer "F.Fab")
		)
		(fp_line
			(start -0.199 0.2)
			(end -0.199 0.1)
			(stroke
				(width 0.15)
				(type solid)
			)
			(layer "F.Fab")
		)
		(fp_line
			(start -0.101 0)
			(end 0.201 0.2)
			(stroke
				(width 0.15)
				(type solid)
			)
			(layer "F.Fab")
		)
		(fp_line
			(start 0.201 -0.202)
			(end -0.101 0)
			(stroke
				(width 0.15)
				(type solid)
			)
			(layer "F.Fab")
		)
		(fp_line
			(start 0.201 0)
			(end 0.201 -0.202)
			(stroke
				(width 0.15)
				(type solid)
			)
			(layer "F.Fab")
		)
		(fp_line
			(start 0.201 0.2)
			(end 0.201 0)
			(stroke
				(width 0.15)
				(type solid)
			)
			(layer "F.Fab")
		)
		(fp_line
			(start 0.599 0)
			(end 0.201 0)
			(stroke
				(width 0.15)
				(type solid)
			)
			(layer "F.Fab")
		)
		(fp_rect
			(start 0.848 0.4)
			(end -0.85 -0.402)
			(stroke
				(width 0.15)
				(type solid)
			)
			(fill no)
			(layer "F.Fab")
		)
		(pad "1" smd roundrect
			(at -0.7 0 180)
			(size 0.8 1)
			(layers "F.Cu" "F.Mask" "F.Paste")
			(roundrect_rratio 0.2)
			(net 22 "Net-(D20-C)")
			(pinfunction "C")
			(pintype "passive")
		)
		(pad "2" smd roundrect
			(at 0.7 0 180)
			(size 0.8 1)
			(layers "F.Cu" "F.Mask" "F.Paste")
			(roundrect_rratio 0.2)
			(net 779 "Net-(D20-A)")
			(pinfunction "A")
			(pintype "passive")
		)
	)
	(footprint "antmicro-footprints:SOT-23-3"
		(layer "F.Cu")
		(at 158.7 145.55 90)
		(property "Reference" "U41"
			(at -1 2.55 90)
			(layer "F.SilkS")
			(effects
				(font
					(size 0.7 0.7)
					(thickness 0.15)
				)
				(justify left bottom)
			)
		)
		(property "Value" "REF3012AIDBZT"
			(at -1.9 2.7 90)
			(layer "F.Fab")
			(effects
				(font
					(size 0.7 0.7)
					(thickness 0.15)
				)
				(justify left bottom)
			)
		)
		(property "Description" "Voltage Reference, Low Power, Low Dropout, Series"
			(at 0 0 90)
			(layer "F.Fab")
			(hide yes)
			(effects
				(font
					(size 1.27 1.27)
					(thickness 0.15)
				)
			)
		)
		(property "Author" "Antmicro"
			(at 304.25 -13.15 0)
			(layer "F.Fab")
			(hide yes)
			(effects
				(font
					(size 1 1)
					(thickness 0.15)
				)
			)
		)
		(property "License" "Apache-2.0"
			(at 304.25 -13.15 0)
			(layer "F.Fab")
			(hide yes)
			(effects
				(font
					(size 1 1)
					(thickness 0.15)
				)
			)
		)
		(property "MPN" "REF3012AIDBZT"
			(at 304.25 -13.15 0)
			(layer "F.Fab")
			(hide yes)
			(effects
				(font
					(size 1 1)
					(thickness 0.15)
				)
			)
		)
		(property "Manufacturer" "Texas Instruments"
			(at 304.25 -13.15 0)
			(layer "F.Fab")
			(hide yes)
			(effects
				(font
					(size 1 1)
					(thickness 0.15)
				)
			)
		)
		(sheetname "DC-DC Converters")
		(sheetfile "dc-dc.kicad_sch")
		(attr smd)
		(fp_line
			(start 0.7 -1.5)
			(end -0.7 -1.5)
			(stroke
				(width 0.15)
				(type solid)
			)
			(layer "F.SilkS")
		)
		(fp_line
			(start -0.85 -1.35)
			(end -0.7 -1.5)
			(stroke
				(width 0.15)
				(type solid)
			)
			(layer "F.SilkS")
		)
		(fp_line
			(start -1.45 -1.35)
			(end -0.85 -1.35)
			(stroke
				(width 0.15)
				(type solid)
			)
			(layer "F.SilkS")
		)
		(fp_line
			(start 0.7 -0.4)
			(end 0.7 -1.5)
			(stroke
				(width 0.15)
				(type solid)
			)
			(layer "F.SilkS")
		)
		(fp_line
			(start 0.7 0.4)
			(end 0.7 1.5)
			(stroke
				(width 0.15)
				(type solid)
			)
			(layer "F.SilkS")
		)
		(fp_line
			(start 0.7 1.5)
			(end -0.7 1.5)
			(stroke
				(width 0.15)
				(type solid)
			)
			(layer "F.SilkS")
		)
		(fp_line
			(start -0.7 1.5)
			(end -0.7 1.35)
			(stroke
				(width 0.15)
				(type solid)
			)
			(layer "F.SilkS")
		)
		(fp_line
			(start 0.825 -1.6)
			(end 0.825 -0.45)
			(stroke
				(width 0.05)
				(type solid)
			)
			(layer "F.CrtYd")
		)
		(fp_line
			(start -0.9 -1.6)
			(end 0.825 -1.6)
			(stroke
				(width 0.05)
				(type solid)
			)
			(layer "F.CrtYd")
		)
		(fp_line
			(start -0.9 -1.6)
			(end -0.9 -1.4)
			(stroke
				(width 0.05)
				(type solid)
			)
			(layer "F.CrtYd")
		)
		(fp_line
			(start -0.9 -1.4)
			(end -1.75 -1.4)
			(stroke
				(width 0.05)
				(type solid)
			)
			(layer "F.CrtYd")
		)
		(fp_line
			(start -0.85 -0.5)
			(end -1.75 -0.5)
			(stroke
				(width 0.05)
				(type solid)
			)
			(layer "F.CrtYd")
		)
		(fp_line
			(start -1.75 -0.5)
			(end -1.75 -1.4)
			(stroke
				(width 0.05)
				(type solid)
			)
			(layer "F.CrtYd")
		)
		(fp_line
			(start 1.75 -0.45)
			(end 1.75 0.45)
			(stroke
				(width 0.05)
				(type solid)
			)
			(layer "F.CrtYd")
		)
		(fp_line
			(start 0.825 -0.45)
			(end 1.75 -0.45)
			(stroke
				(width 0.05)
				(type solid)
			)
			(layer "F.CrtYd")
		)
		(fp_line
			(start 1.75 0.45)
			(end 0.85 0.45)
			(stroke
				(width 0.05)
				(type solid)
			)
			(layer "F.CrtYd")
		)
		(fp_line
			(start 0.85 0.45)
			(end 0.85 1.65)
			(stroke
				(width 0.05)
				(type solid)
			)
			(layer "F.CrtYd")
		)
		(fp_line
			(start -0.85 0.5)
			(end -0.85 -0.5)
			(stroke
				(width 0.05)
				(type solid)
			)
			(layer "F.CrtYd")
		)
		(fp_line
			(start -1.75 0.5)
			(end -0.85 0.5)
			(stroke
				(width 0.05)
				(type solid)
			)
			(layer "F.CrtYd")
		)
		(fp_line
			(start -0.85 1.4)
			(end -1.75 1.4)
			(stroke
				(width 0.05)
				(type solid)
			)
			(layer "F.CrtYd")
		)
		(fp_line
			(start -1.75 1.4)
			(end -1.75 0.5)
			(stroke
				(width 0.05)
				(type solid)
			)
			(layer "F.CrtYd")
		)
		(fp_line
			(start 0.85 1.65)
			(end -0.85 1.65)
			(stroke
				(width 0.05)
				(type solid)
			)
			(layer "F.CrtYd")
		)
		(fp_line
			(start -0.85 1.65)
			(end -0.85 1.4)
			(stroke
				(width 0.05)
				(type solid)
			)
			(layer "F.CrtYd")
		)
		(fp_line
			(start -0.437 -1.526)
			(end 0.688 -1.526)
			(stroke
				(width 0.15)
				(type solid)
			)
			(layer "F.Fab")
		)
		(fp_line
			(start -0.437 -1.526)
			(end -0.712 -1.325)
			(stroke
				(width 0.15)
				(type solid)
			)
			(layer "F.Fab")
		)
		(fp_line
			(start -0.712 -1.325)
			(end -0.712 1.523)
			(stroke
				(width 0.15)
				(type solid)
			)
			(layer "F.Fab")
		)
		(fp_line
			(start 0.688 1.519)
			(end 0.688 -1.52)
			(stroke
				(width 0.15)
				(type solid)
			)
			(layer "F.Fab")
		)
		(fp_line
			(start -0.712 1.519)
			(end 0.688 1.519)
			(stroke
				(width 0.15)
				(type solid)
			)
			(layer "F.Fab")
		)
		(pad "1" smd roundrect
			(at -1.1 -0.951 90)
			(size 1 0.6)
			(layers "F.Cu" "F.Mask" "F.Paste")
			(roundrect_rratio 0.15)
			(net 747 "/DC-DC Converters/1V85_OUT")
			(pinfunction "IN")
			(pintype "power_in")
		)
		(pad "2" smd roundrect
			(at -1.1 0.949 90)
			(size 1 0.6)
			(layers "F.Cu" "F.Mask" "F.Paste")
			(roundrect_rratio 0.15)
			(net 15 "Net-(U41-OUT)")
			(pinfunction "OUT")
			(pintype "output")
		)
		(pad "3" smd roundrect
			(at 1.1 -0.0005 90)
			(size 1 0.6)
			(layers "F.Cu" "F.Mask" "F.Paste")
			(roundrect_rratio 0.15)
			(net 1 "GND")
			(pinfunction "GND")
			(pintype "passive")
		)
	)
)
